(kicad_pcb
	(version 20260206)
	(generator "pcbnew")
	(generator_version "10.0")
	(general
		(thickness 1.6)
		(legacy_teardrops no)
	)
	(paper "A4")
	(title_block
		(title "v2-tray-backplane — ms_tbp_v2.brd")
		(comment 1 "Open CloudServer (Microsoft) / footprints 81-83 of 164")
	)
	(layers
		(0 "F.Cu" signal "TOP")
		(4 "In1.Cu" signal "LYR2")
		(6 "In2.Cu" signal "LYR3")
		(8 "In3.Cu" signal "LYR4")
		(10 "In4.Cu" signal "LYR5")
		(12 "In5.Cu" signal "LYR6")
		(14 "In6.Cu" signal "LYR7")
		(2 "B.Cu" signal "BOTTOM")
		(9 "F.Adhes" user "F.Adhesive")
		(11 "B.Adhes" user "B.Adhesive")
		(13 "F.Paste" user "Package Geometry/Pastemask Top")
		(15 "B.Paste" user "Package Geometry/Pastemask Bottom")
		(5 "F.SilkS" user "Ref Des/Silkscreen Top")
		(7 "B.SilkS" user "Ref Des/Silkscreen Bottom")
		(1 "F.Mask" user "Board Geometry/Soldermask Top")
		(3 "B.Mask" user "Board Geometry/Soldermask Bottom")
		(17 "Dwgs.User" user "User.Drawings")
		(19 "Cmts.User" user "User.Comments")
		(21 "Eco1.User" user "User.Eco1")
		(23 "Eco2.User" user "User.Eco2")
		(25 "Edge.Cuts" user "Board Geometry/Outline")
		(27 "Margin" user)
		(31 "F.CrtYd" user "Package Geometry/Place Bound Top")
		(29 "B.CrtYd" user "Package Geometry/Place Bound Bottom")
		(35 "F.Fab" user "Ref Des/Assembly Top")
		(33 "B.Fab" user "Ref Des/Assembly Bottom")
	)
	(footprint ""
		(layer "F.Cu")
		(at -26.68 45.360001 180)
		(property "Reference" "J23"
			(at 5 16.084901 0)
			(unlocked yes)
			(layer "F.SilkS")
			(effects
				(font
					(size 0.762 0.5334)
					(thickness 0.1016)
				)
			)
		)
		(property "Value" ""
			(at 0 0 180)
			(layer "F.Fab")
			(effects
				(font
					(size 1.27 1.27)
				)
			)
		)
		(duplicate_pad_numbers_are_jumpers no)
		(fp_line
			(start 10.950001 15.3)
			(end -0.950001 15.3)
			(stroke
				(width 0.127)
				(type default)
			)
			(layer "F.SilkS")
		)
		(fp_line
			(start 10.950001 -11.999999)
			(end 10.950001 15.3)
			(stroke
				(width 0.127)
				(type default)
			)
			(layer "F.SilkS")
		)
		(fp_line
			(start -0.950001 15.3)
			(end -0.950001 -11.999999)
			(stroke
				(width 0.127)
				(type default)
			)
			(layer "F.SilkS")
		)
		(fp_line
			(start -0.950001 -11.999999)
			(end 10.950001 -11.999999)
			(stroke
				(width 0.127)
				(type default)
			)
			(layer "F.SilkS")
		)
		(fp_poly
			(pts
				(arc
					(start -4.93 12.500001)
					(mid -3.486036 15.986037)
					(end 0 17.430001)
				)
				(arc
					(start 10 17.430001)
					(mid 13.486036 15.986037)
					(end 14.930001 12.500001)
				)
				(arc
					(start 14.930001 -0.1)
					(mid 13.486037 -3.586037)
					(end 10 -5.03)
				)
				(arc
					(start 0 -5.03)
					(mid -3.486036 -3.586036)
					(end -4.93 -0.1)
				)
			)
			(stroke
				(width 0)
				(type default)
			)
			(fill no)
			(layer "B.CrtYd")
		)
		(fp_poly
			(pts
				(xy 11.949999 16.300001) (xy -1.950001 16.300001) (xy -1.950001 -12.999999) (xy 11.949999 -12.999999)
			)
			(stroke
				(width 0)
				(type default)
			)
			(fill no)
			(layer "F.CrtYd")
		)
		(fp_line
			(start 10.950001 15.3)
			(end -0.950001 15.3)
			(stroke
				(width 0.1)
				(type default)
			)
			(layer "F.Fab")
		)
		(fp_line
			(start 10.950001 -11.999999)
			(end 10.950001 15.3)
			(stroke
				(width 0.1)
				(type default)
			)
			(layer "F.Fab")
		)
		(fp_line
			(start -0.950001 15.3)
			(end -0.950001 -11.999999)
			(stroke
				(width 0.1)
				(type default)
			)
			(layer "F.Fab")
		)
		(fp_line
			(start -0.950001 -11.999999)
			(end 10.950001 -11.999999)
			(stroke
				(width 0.1)
				(type default)
			)
			(layer "F.Fab")
		)
		(fp_text user "I6"
			(at 12.130999 11.0809 0)
			(unlocked yes)
			(layer "F.SilkS")
			(effects
				(font
					(size 0.762 0.5334)
					(thickness 0.1016)
				)
			)
		)
		(fp_text user "E6"
			(at 12.130999 5.480901 0)
			(unlocked yes)
			(layer "F.SilkS")
			(effects
				(font
					(size 0.762 0.5334)
					(thickness 0.1016)
				)
			)
		)
		(fp_text user "A6"
			(at 12.130999 -0.1191 0)
			(unlocked yes)
			(layer "F.SilkS")
			(effects
				(font
					(size 0.762 0.5334)
					(thickness 0.1016)
				)
			)
		)
		(fp_text user "*"
			(at -1.5 -1.328549 0)
			(unlocked yes)
			(layer "F.SilkS")
			(effects
				(font
					(size 0.381 0.381)
					(thickness 0.381)
				)
			)
		)
		(fp_text user "I1"
			(at -1.876999 10.9539 0)
			(unlocked yes)
			(layer "F.SilkS")
			(effects
				(font
					(size 0.762 0.5334)
					(thickness 0.1016)
				)
			)
		)
		(fp_text user "E1"
			(at -1.876999 5.353901 0)
			(unlocked yes)
			(layer "F.SilkS")
			(effects
				(font
					(size 0.762 0.5334)
					(thickness 0.1016)
				)
			)
		)
		(fp_text user "A1"
			(at -1.876999 -0.2461 0)
			(unlocked yes)
			(layer "F.SilkS")
			(effects
				(font
					(size 0.762 0.5334)
					(thickness 0.1016)
				)
			)
		)
		(fp_text user "I8"
			(at 11.55 11.0809 0)
			(unlocked yes)
			(layer "B.SilkS")
			(effects
				(font
					(size 0.762 0.5334)
					(thickness 0.1016)
				)
				(justify mirror)
			)
		)
		(fp_text user "E8"
			(at 11.55 5.480901 0)
			(unlocked yes)
			(layer "B.SilkS")
			(effects
				(font
					(size 0.762 0.5334)
					(thickness 0.1016)
				)
				(justify mirror)
			)
		)
		(fp_text user "A8"
			(at 11.55 -0.1191 0)
			(unlocked yes)
			(layer "B.SilkS")
			(effects
				(font
					(size 0.762 0.5334)
					(thickness 0.1016)
				)
				(justify mirror)
			)
		)
		(fp_text user "E1"
			(at -1.29524 5.774101 0)
			(unlocked yes)
			(layer "B.SilkS")
			(effects
				(font
					(size 0.762 0.5334)
					(thickness 0.1016)
				)
				(justify mirror)
			)
		)
		(fp_text user "I1"
			(at -1.5 11.0809 0)
			(unlocked yes)
			(layer "B.SilkS")
			(effects
				(font
					(size 0.762 0.5334)
					(thickness 0.1016)
				)
				(justify mirror)
			)
		)
		(fp_text user "A1"
			(at -1.549999 -0.1191 0)
			(unlocked yes)
			(layer "B.SilkS")
			(effects
				(font
					(size 0.762 0.5334)
					(thickness 0.1016)
				)
				(justify mirror)
			)
		)
		(pad "A1" thru_hole circle
			(at 0 0 180)
			(size 0.8128 0.8128)
			(drill 0.508)
			(layers "*.Cu" "*.Mask")
			(remove_unused_layers no)
			(net "SAS_B2_TX1P")
		)
		(pad "A2" thru_hole circle
			(at 2.000001 -0.1 180)
			(size 0.8128 0.8128)
			(drill 0.508)
			(layers "*.Cu" "*.Mask")
			(remove_unused_layers no)
			(net "GND")
		)
		(pad "A3" thru_hole circle
			(at 4 0 180)
			(size 0.8128 0.8128)
			(drill 0.508)
			(layers "*.Cu" "*.Mask")
			(remove_unused_layers no)
			(net "SERIAL_B2_TX1")
		)
		(pad "A4" thru_hole circle
			(at 6.000001 -0.1 180)
			(size 0.8128 0.8128)
			(drill 0.508)
			(layers "*.Cu" "*.Mask")
			(remove_unused_layers no)
			(net "GND")
		)
		(pad "A5" thru_hole circle
			(at 7.999999 0 180)
			(size 0.8128 0.8128)
			(drill 0.508)
			(layers "*.Cu" "*.Mask")
			(remove_unused_layers no)
			(net "SAS_B2_TX6P")
		)
		(pad "A6" thru_hole circle
			(at 10 -0.1 180)
			(size 0.8128 0.8128)
			(drill 0.508)
			(layers "*.Cu" "*.Mask")
			(remove_unused_layers no)
			(net "GND")
		)
		(pad "B1" thru_hole circle
			(at 0 1.4 180)
			(size 0.8128 0.8128)
			(drill 0.508)
			(layers "*.Cu" "*.Mask")
			(remove_unused_layers no)
			(net "SAS_B2_TX1N")
		)
		(pad "B2" thru_hole circle
			(at 2.000001 1.3 180)
			(size 0.8128 0.8128)
			(drill 0.508)
			(layers "*.Cu" "*.Mask")
			(remove_unused_layers no)
			(net "SAS_B2_RX3P")
		)
		(pad "B3" thru_hole circle
			(at 4 1.4 180)
			(size 0.8128 0.8128)
			(drill 0.508)
			(layers "*.Cu" "*.Mask")
			(remove_unused_layers no)
			(net "SERIAL_B2_RX1")
		)
		(pad "B4" thru_hole circle
			(at 6.000001 1.3 180)
			(size 0.8128 0.8128)
			(drill 0.508)
			(layers "*.Cu" "*.Mask")
			(remove_unused_layers no)
			(net "JBOD_B2_MATED_N")
		)
		(pad "B5" thru_hole circle
			(at 7.999999 1.4 180)
			(size 0.8128 0.8128)
			(drill 0.508)
			(layers "*.Cu" "*.Mask")
			(remove_unused_layers no)
			(net "SAS_B2_TX6N")
		)
		(pad "B6" thru_hole circle
			(at 10 1.3 180)
			(size 0.8128 0.8128)
			(drill 0.508)
			(layers "*.Cu" "*.Mask")
			(remove_unused_layers no)
			(net "SAS_B2_RX8P")
		)
		(pad "C1" thru_hole circle
			(at 0 2.799999 180)
			(size 0.8128 0.8128)
			(drill 0.508)
			(layers "*.Cu" "*.Mask")
			(remove_unused_layers no)
			(net "GND")
		)
		(pad "C2" thru_hole circle
			(at 2.000001 2.7 180)
			(size 0.8128 0.8128)
			(drill 0.508)
			(layers "*.Cu" "*.Mask")
			(remove_unused_layers no)
			(net "SAS_B2_RX3N")
		)
		(pad "C3" thru_hole circle
			(at 4 2.799999 180)
			(size 0.8128 0.8128)
			(drill 0.508)
			(layers "*.Cu" "*.Mask")
			(remove_unused_layers no)
			(net "GND")
		)
		(pad "C4" thru_hole circle
			(at 6.000001 2.7 180)
			(size 0.8128 0.8128)
			(drill 0.508)
			(layers "*.Cu" "*.Mask")
			(remove_unused_layers no)
			(net "BLADE_B2_EN1")
		)
		(pad "C5" thru_hole circle
			(at 7.999999 2.799999 180)
			(size 0.8128 0.8128)
			(drill 0.508)
			(layers "*.Cu" "*.Mask")
			(remove_unused_layers no)
			(net "GND")
		)
		(pad "C6" thru_hole circle
			(at 10 2.7 180)
			(size 0.8128 0.8128)
			(drill 0.508)
			(layers "*.Cu" "*.Mask")
			(remove_unused_layers no)
			(net "SAS_B2_RX8N")
		)
		(pad "D1" thru_hole circle
			(at 0 4.199999 180)
			(size 0.8128 0.8128)
			(drill 0.508)
			(layers "*.Cu" "*.Mask")
			(remove_unused_layers no)
			(net "SAS_B2_RX1P")
		)
		(pad "D2" thru_hole circle
			(at 2.000001 4.099999 180)
			(size 0.8128 0.8128)
			(drill 0.508)
			(layers "*.Cu" "*.Mask")
			(remove_unused_layers no)
			(net "GND")
		)
		(pad "D3" thru_hole circle
			(at 4 4.199999 180)
			(size 0.8128 0.8128)
			(drill 0.508)
			(layers "*.Cu" "*.Mask")
			(remove_unused_layers no)
			(net "SAS_B2_RX4P")
		)
		(pad "D4" thru_hole circle
			(at 6.000001 4.099999 180)
			(size 0.8128 0.8128)
			(drill 0.508)
			(layers "*.Cu" "*.Mask")
			(remove_unused_layers no)
			(net "GND")
		)
		(pad "D5" thru_hole circle
			(at 7.999999 4.199999 180)
			(size 0.8128 0.8128)
			(drill 0.508)
			(layers "*.Cu" "*.Mask")
			(remove_unused_layers no)
			(net "SAS_B2_RX6P")
		)
		(pad "D6" thru_hole circle
			(at 10 4.099999 180)
			(size 0.8128 0.8128)
			(drill 0.508)
			(layers "*.Cu" "*.Mask")
			(remove_unused_layers no)
			(net "GND")
		)
		(pad "E1" thru_hole circle
			(at 0 5.599999 180)
			(size 0.8128 0.8128)
			(drill 0.508)
			(layers "*.Cu" "*.Mask")
			(remove_unused_layers no)
			(net "SAS_B2_RX1N")
		)
		(pad "E2" thru_hole circle
			(at 2.000001 5.499999 180)
			(size 0.8128 0.8128)
			(drill 0.508)
			(layers "*.Cu" "*.Mask")
			(remove_unused_layers no)
			(net "SAS_B2_TX3P")
		)
		(pad "E3" thru_hole circle
			(at 4 5.599999 180)
			(size 0.8128 0.8128)
			(drill 0.508)
			(layers "*.Cu" "*.Mask")
			(remove_unused_layers no)
			(net "SAS_B2_RX4N")
		)
		(pad "E4" thru_hole circle
			(at 6.000001 5.499999 180)
			(size 0.8128 0.8128)
			(drill 0.508)
			(layers "*.Cu" "*.Mask")
			(remove_unused_layers no)
			(net "SAS_B2_TX5P")
		)
		(pad "E5" thru_hole circle
			(at 7.999999 5.599999 180)
			(size 0.8128 0.8128)
			(drill 0.508)
			(layers "*.Cu" "*.Mask")
			(remove_unused_layers no)
			(net "SAS_B2_RX6N")
		)
		(pad "E6" thru_hole circle
			(at 10 5.499999 180)
			(size 0.8128 0.8128)
			(drill 0.508)
			(layers "*.Cu" "*.Mask")
			(remove_unused_layers no)
			(net "SAS_B2_TX8P")
		)
		(pad "F1" thru_hole circle
			(at 0 7.000001 180)
			(size 0.8128 0.8128)
			(drill 0.508)
			(layers "*.Cu" "*.Mask")
			(remove_unused_layers no)
			(net "GND")
		)
		(pad "F2" thru_hole circle
			(at 2.000001 6.899999 180)
			(size 0.8128 0.8128)
			(drill 0.508)
			(layers "*.Cu" "*.Mask")
			(remove_unused_layers no)
			(net "SAS_B2_TX3N")
		)
		(pad "F3" thru_hole circle
			(at 4 7.000001 180)
			(size 0.8128 0.8128)
			(drill 0.508)
			(layers "*.Cu" "*.Mask")
			(remove_unused_layers no)
			(net "GND")
		)
		(pad "F4" thru_hole circle
			(at 6.000001 6.899999 180)
			(size 0.8128 0.8128)
			(drill 0.508)
			(layers "*.Cu" "*.Mask")
			(remove_unused_layers no)
			(net "SAS_B2_TX5N")
		)
		(pad "F5" thru_hole circle
			(at 7.999999 7.000001 180)
			(size 0.8128 0.8128)
			(drill 0.508)
			(layers "*.Cu" "*.Mask")
			(remove_unused_layers no)
			(net "GND")
		)
		(pad "F6" thru_hole circle
			(at 10 6.899999 180)
			(size 0.8128 0.8128)
			(drill 0.508)
			(layers "*.Cu" "*.Mask")
			(remove_unused_layers no)
			(net "SAS_B2_TX8N")
		)
		(pad "G1" thru_hole circle
			(at 0 8.400001 180)
			(size 0.8128 0.8128)
			(drill 0.508)
			(layers "*.Cu" "*.Mask")
			(remove_unused_layers no)
			(net "SAS_B2_TX2P")
		)
		(pad "G2" thru_hole circle
			(at 2.000001 8.300001 180)
			(size 0.8128 0.8128)
			(drill 0.508)
			(layers "*.Cu" "*.Mask")
			(remove_unused_layers no)
			(net "GND")
		)
		(pad "G3" thru_hole circle
			(at 4 8.400001 180)
			(size 0.8128 0.8128)
			(drill 0.508)
			(layers "*.Cu" "*.Mask")
			(remove_unused_layers no)
			(net "SAS_B2_TX4P")
		)
		(pad "G4" thru_hole circle
			(at 6.000001 8.300001 180)
			(size 0.8128 0.8128)
			(drill 0.508)
			(layers "*.Cu" "*.Mask")
			(remove_unused_layers no)
			(net "GND")
		)
		(pad "G5" thru_hole circle
			(at 7.999999 8.400001 180)
			(size 0.8128 0.8128)
			(drill 0.508)
			(layers "*.Cu" "*.Mask")
			(remove_unused_layers no)
			(net "SAS_B2_TX7P")
		)
		(pad "G6" thru_hole circle
			(at 10 8.300001 180)
			(size 0.8128 0.8128)
			(drill 0.508)
			(layers "*.Cu" "*.Mask")
			(remove_unused_layers no)
			(net "GND")
		)
		(pad "H1" thru_hole circle
			(at 0 9.800001 180)
			(size 0.8128 0.8128)
			(drill 0.508)
			(layers "*.Cu" "*.Mask")
			(remove_unused_layers no)
			(net "SAS_B2_TX2N")
		)
		(pad "H2" thru_hole circle
			(at 2.000001 9.700001 180)
			(size 0.8128 0.8128)
			(drill 0.508)
			(layers "*.Cu" "*.Mask")
			(remove_unused_layers no)
			(net "SAS_B2_RX2P")
		)
		(pad "H3" thru_hole circle
			(at 4 9.800001 180)
			(size 0.8128 0.8128)
			(drill 0.508)
			(layers "*.Cu" "*.Mask")
			(remove_unused_layers no)
			(net "SAS_B2_TX4N")
		)
		(pad "H4" thru_hole circle
			(at 6.000001 9.700001 180)
			(size 0.8128 0.8128)
			(drill 0.508)
			(layers "*.Cu" "*.Mask")
			(remove_unused_layers no)
			(net "SAS_B2_RX5P")
		)
		(pad "H5" thru_hole circle
			(at 7.999999 9.800001 180)
			(size 0.8128 0.8128)
			(drill 0.508)
			(layers "*.Cu" "*.Mask")
			(remove_unused_layers no)
			(net "SAS_B2_TX7N")
		)
		(pad "H6" thru_hole circle
			(at 10 9.700001 180)
			(size 0.8128 0.8128)
			(drill 0.508)
			(layers "*.Cu" "*.Mask")
			(remove_unused_layers no)
			(net "SAS_B2_RX7P")
		)
		(pad "I1" thru_hole circle
			(at 0 11.2 180)
			(size 0.8128 0.8128)
			(drill 0.508)
			(layers "*.Cu" "*.Mask")
			(remove_unused_layers no)
			(net "GND")
		)
		(pad "I2" thru_hole circle
			(at 2.000001 11.100001 180)
			(size 0.8128 0.8128)
			(drill 0.508)
			(layers "*.Cu" "*.Mask")
			(remove_unused_layers no)
			(net "SAS_B2_RX2N")
		)
		(pad "I3" thru_hole circle
			(at 4 11.2 180)
			(size 0.8128 0.8128)
			(drill 0.508)
			(layers "*.Cu" "*.Mask")
			(remove_unused_layers no)
			(net "GND")
		)
		(pad "I4" thru_hole circle
			(at 6.000001 11.100001 180)
			(size 0.8128 0.8128)
			(drill 0.508)
			(layers "*.Cu" "*.Mask")
			(remove_unused_layers no)
			(net "SAS_B2_RX5N")
		)
		(pad "I5" thru_hole circle
			(at 7.999999 11.2 180)
			(size 0.8128 0.8128)
			(drill 0.508)
			(layers "*.Cu" "*.Mask")
			(remove_unused_layers no)
			(net "GND")
		)
		(pad "I6" thru_hole circle
			(at 10 11.100001 180)
			(size 0.8128 0.8128)
			(drill 0.508)
			(layers "*.Cu" "*.Mask")
			(remove_unused_layers no)
			(net "SAS_B2_RX7N")
		)
		(pad "J2" thru_hole circle
			(at 2.000001 12.5 180)
			(size 0.8128 0.8128)
			(drill 0.508)
			(layers "*.Cu" "*.Mask")
			(remove_unused_layers no)
			(net "GND")
		)
		(pad "J4" thru_hole circle
			(at 6.000001 12.5 180)
			(size 0.8128 0.8128)
			(drill 0.508)
			(layers "*.Cu" "*.Mask")
			(remove_unused_layers no)
			(net "GND")
		)
		(pad "J6" thru_hole circle
			(at 10 12.5 180)
			(size 0.8128 0.8128)
			(drill 0.508)
			(layers "*.Cu" "*.Mask")
			(remove_unused_layers no)
			(net "GND")
		)
	)
	(footprint ""
		(layer "F.Cu")
		(at -266.2174 4.2164 180)
		(property "Reference" "C39"
			(at -3.3655 0.04572 0)
			(unlocked yes)
			(layer "F.SilkS")
			(effects
				(font
					(size 0.762 0.5334)
					(thickness 0.1016)
				)
			)
		)
		(property "Value" ""
			(at 0 0 180)
			(layer "F.Fab")
			(effects
				(font
					(size 1.27 1.27)
				)
			)
		)
		(duplicate_pad_numbers_are_jumpers no)
		(fp_line
			(start 0 -0.381)
			(end 0 0.381)
			(stroke
				(width 0.127)
				(type default)
			)
			(layer "F.SilkS")
		)
		(fp_poly
			(pts
				(xy 1.2533 0.656399) (xy -1.253299 0.656399) (xy -1.253299 -0.6564) (xy 1.2533 -0.6564)
			)
			(stroke
				(width 0)
				(type default)
			)
			(fill no)
			(layer "F.CrtYd")
		)
		(fp_line
			(start 0.762 0.381)
			(end 0.762 -0.381)
			(stroke
				(width 0.1)
				(type default)
			)
			(layer "F.Fab")
		)
		(fp_line
			(start 0.762 -0.381)
			(end -0.762 -0.381)
			(stroke
				(width 0.1)
				(type default)
			)
			(layer "F.Fab")
		)
		(fp_line
			(start -0.762 0.381)
			(end 0.762 0.381)
			(stroke
				(width 0.1)
				(type default)
			)
			(layer "F.Fab")
		)
		(fp_line
			(start -0.762 -0.381)
			(end -0.762 0.381)
			(stroke
				(width 0.1)
				(type default)
			)
			(layer "F.Fab")
		)
		(pad "1" smd rect
			(at -0.6477 0 180)
			(size 0.7112 0.8128)
			(layers "F.Cu" "F.Mask" "F.Paste")
			(net "P3V3_B1_QSFP")
		)
		(pad "2" smd rect
			(at 0.6477 0)
			(size 0.7112 0.8128)
			(layers "F.Cu" "F.Mask" "F.Paste")
			(net "GND")
		)
	)
	(footprint ""
		(layer "F.Cu")
		(at -276.9362 45.6438)
		(property "Reference" "FS2"
			(at 0.0762 1.1303 0)
			(unlocked yes)
			(layer "F.SilkS")
			(effects
				(font
					(size 0.762 0.5334)
					(thickness 0.1016)
				)
			)
		)
		(property "Value" ""
			(at 0 0 0)
			(layer "F.Fab")
			(effects
				(font
					(size 1.27 1.27)
				)
			)
		)
		(duplicate_pad_numbers_are_jumpers no)
		(fp_poly
			(pts
				(xy -1.002101 0.504) (xy -1.002101 -0.503999) (xy 1.002101 -0.503999) (xy 1.002101 0.504)
			)
			(stroke
				(width 0)
				(type default)
			)
			(fill no)
			(layer "F.CrtYd")
		)
		(fp_line
			(start -0.499999 -0.249999)
			(end -0.499999 0.25)
			(stroke
				(width 0.1)
				(type default)
			)
			(layer "F.Fab")
		)
		(fp_line
			(start -0.499999 0.25)
			(end 0.499999 0.25)
			(stroke
				(width 0.1)
				(type default)
			)
			(layer "F.Fab")
		)
		(fp_line
			(start 0.499999 -0.249999)
			(end -0.499999 -0.249999)
			(stroke
				(width 0.1)
				(type default)
			)
			(layer "F.Fab")
		)
		(fp_line
			(start 0.499999 0.25)
			(end 0.499999 -0.249999)
			(stroke
				(width 0.1)
				(type default)
			)
			(layer "F.Fab")
		)
		(pad "1" smd rect
			(at -0.459999 0 90)
			(size 0.508 0.5842)
			(layers "F.Cu" "F.Mask" "F.Paste")
			(net "UNNAMED_4_FERRITE_I151_B")
		)
		(pad "2" smd rect
			(at 0.459999 0 90)
			(size 0.508 0.5842)
			(layers "F.Cu" "F.Mask" "F.Paste")
			(net "P3V3_B1_QSFP")
		)
	)
)
